FILE_TYPE = MULTI_PHYS_TABLE;

PART 'APX80929SAG7'

{========================================================================================}
:VALUE            | PART_TYPE | MATERIAL | PART_NUMBER    = STANDARD | LIFECYCLE      | PART_NUMBER   | JEDEC_TYPE    | DESCRIPTION                          | MANUFTR | MANUF_PN         | RD_CMPLS_LVL | CMPLS_LVL | FROM_PJ       | CLASS | DIP_SMD | DATA                      | EE_CHECK_LIST | FP_ECN | PSL | CREATOR | STATUS | CREATEDAY  ;
{========================================================================================}
 'APX809-29SAG-7' | 'SMLF'    | 'IC'     | 'AL080929000'(!) = ''       | ''               | 'AL080929000' |'SOT23_123XI'| 'IC OTHER(3P) APX809-29SAG-7(SOT23)' | 'DDS'   | 'APX809-29SAG-7' | 'EP(V1)'     | 'EP(V1)'  | 'S2VA-JOSEPH' | 'IC'  | ''      | 'DDS_APX809-810_rev4.pdf' | ''            | ''     | ''  | ''      | ''     | '20130717'
 'APX809-29SAG-7' | 'SMLF'    | 'EMPTY'  | 'AL080929000'(!) = ''       | ''               | 'AL080929000' |'SOT23_123XI'| 'IC OTHER(3P) APX809-29SAG-7(SOT23)' | 'DDS'   | 'APX809-29SAG-7' | 'EP(V1)'     | 'EP(V1)'  | 'S2VA-JOSEPH' | 'IC'  | ''      | 'DDS_APX809-810_rev4.pdf' | ''            | ''     | ''  | ''      | ''     | '20130717'

END_PART

END.

